FILE_TYPE = MULTI_PHYS_TABLE;

PART 'MX25L51245GMI10G'

{========================================================================================}
:VALUE               | PART_TYPE | MATERIAL | PART_NUMBER    = STANDARD | LIFECYCLE      | PART_NUMBER   | JEDEC_TYPE             | DESCRIPTION                           | MANUFTR | MANUF_PN            | RD_CMPLS_LVL | CMPLS_LVL | FROM_PJ   | CLASS | DIP_SMD | DATA                        | EE_CHECK_LIST | FP_ECN | PSL | CREATOR | STATUS | MSD  | ESD_CDM | ESD_HBM | ESD_MM | PIN_LENGTH_SHORT_PIN | PIN_LENGTH_LONG_PIN | CREATEDAY  ;
{========================================================================================}
 'MX25L51245GMI-10G' | 'SMLF'    | 'IC'     | 'AKE3FF00Z00'(!) = 'End of Design'  | 'Comp-Approve'   | 'AKE3FF00Z00' |'SOP16_1-27_10-3X7-52'| 'IC FLASH(16P)MX25L51245GMI-10G(SOP)' | 'MAX'   | 'MX25L51245GMI-10G' | 'EP(V1)'     | 'EP(V1)'  | 'S3C-SEB' | 'IC'  | ''      | 'MAX_MX25L51245GMI-10G.pdf' | ''            | ''     | ''  | ''      | ''     | 'NA' | 'NA'    | 'NA'    | 'NA'   | '0 MILS'             | '0 MILS'            | '20171211'
 'MX25L51245GMI-10G' | 'SMLF'    | 'EMPTY'  | 'AKE3FF00Z00'(!) = 'End of Design'  | 'Comp-Approve'   | 'AKE3FF00Z00' |'SOP16_1-27_10-3X7-52'| 'IC FLASH(16P)MX25L51245GMI-10G(SOP)' | 'MAX'   | 'MX25L51245GMI-10G' | 'EP(V1)'     | 'EP(V1)'  | 'S3C-SEB' | 'IC'  | ''      | 'MAX_MX25L51245GMI-10G.pdf' | ''            | ''     | ''  | ''      | ''     | 'NA' | 'NA'    | 'NA'    | 'NA'   | '0 MILS'             | '0 MILS'            | '20171211'

END_PART

END.

